(kicad_pcb
	(version 20241229)
	(generator "pcbnew")
	(generator_version "9.0")
	(general
		(thickness 1.63)
		(legacy_teardrops no)
	)
	(paper "A4")
	(title_block
		(title "CM4 Baseboard")
		(date "2026-01-05")
		(rev "1.1.1")
		(company "Antmicro Ltd")
		(comment 1 "www.antmicro.com")
		(comment 9 "footprints 46-51 of 506")
	)
	(layers
		(0 "F.Cu" signal)
		(4 "In1.Cu" power)
		(6 "In2.Cu" power)
		(8 "In3.Cu" signal)
		(10 "In4.Cu" signal)
		(2 "B.Cu" signal)
		(9 "F.Adhes" user "F.Adhesive")
		(11 "B.Adhes" user "B.Adhesive")
		(13 "F.Paste" user)
		(15 "B.Paste" user)
		(5 "F.SilkS" user "F.Silkscreen")
		(7 "B.SilkS" user "B.Silkscreen")
		(1 "F.Mask" user)
		(3 "B.Mask" user)
		(17 "Dwgs.User" user "User.Drawings")
		(19 "Cmts.User" user "User.Comments")
		(21 "Eco1.User" user "User.Eco1")
		(23 "Eco2.User" user "User.Eco2")
		(25 "Edge.Cuts" user)
		(27 "Margin" user)
		(31 "F.CrtYd" user "F.Courtyard")
		(29 "B.CrtYd" user "B.Courtyard")
		(35 "F.Fab" user)
		(33 "B.Fab" user)
	)
	(footprint "antmicro-footprints:C_0402_1005Metric"
		(layer "F.Cu")
		(at 87.392962 151.3665 90)
		(descr "Capacitor SMD 0402")
		(tags "capacitor SMD 0402")
		(property "Reference" "C206"
			(at 0.025 -0.425 90)
			(layer "F.SilkS")
			(effects
				(font
					(size 0.7 0.7)
					(thickness 0.15)
				)
				(justify left bottom)
			)
		)
		(property "Value" "C_100n_0402"
			(at -1.022927 2.155213 90)
			(layer "F.Fab")
			(effects
				(font
					(size 0.7 0.7)
					(thickness 0.15)
				)
				(justify left bottom)
			)
		)
		(property "Datasheet" "https://www.murata.com/products/productdetail?partno=GRM155R61H104KE14%23"
			(at 0 0 90)
			(layer "F.Fab")
			(hide yes)
			(effects
				(font
					(size 1.27 1.27)
					(thickness 0.15)
				)
			)
		)
		(property "MPN" "GRM155R61H104KE14D"
			(at 0 0 90)
			(unlocked yes)
			(layer "F.Fab")
			(hide yes)
			(effects
				(font
					(size 1 1)
					(thickness 0.15)
				)
			)
		)
		(property "Manufacturer" "Murata"
			(at 0 0 90)
			(unlocked yes)
			(layer "F.Fab")
			(hide yes)
			(effects
				(font
					(size 1 1)
					(thickness 0.15)
				)
			)
		)
		(property "License" "Apache-2.0"
			(at 0 0 90)
			(unlocked yes)
			(layer "F.Fab")
			(hide yes)
			(effects
				(font
					(size 1 1)
					(thickness 0.15)
				)
			)
		)
		(property "Author" "Antmicro"
			(at 0 0 90)
			(unlocked yes)
			(layer "F.Fab")
			(hide yes)
			(effects
				(font
					(size 1 1)
					(thickness 0.15)
				)
			)
		)
		(property "Val" "100n"
			(at 0 0 90)
			(unlocked yes)
			(layer "F.Fab")
			(hide yes)
			(effects
				(font
					(size 1 1)
					(thickness 0.15)
				)
			)
		)
		(property "Voltage" "50V"
			(at 0 0 90)
			(unlocked yes)
			(layer "F.Fab")
			(hide yes)
			(effects
				(font
					(size 1 1)
					(thickness 0.15)
				)
			)
		)
		(property "Dielectric" "X5R"
			(at 0 0 90)
			(unlocked yes)
			(layer "F.Fab")
			(hide yes)
			(effects
				(font
					(size 1 1)
					(thickness 0.15)
				)
			)
		)
		(sheetname "/Compute module/")
		(sheetfile "compute-module.kicad_sch")
		(attr smd)
		(fp_rect
			(start -0.925 -0.47)
			(end 0.925 0.47)
			(stroke
				(width 0.05)
				(type default)
			)
			(fill no)
			(layer "F.CrtYd")
		)
		(fp_line
			(start 0.504 -0.25)
			(end 0.504 0.248)
			(stroke
				(width 0.15)
				(type solid)
			)
			(layer "F.Fab")
		)
		(fp_line
			(start -0.494 -0.25)
			(end 0.504 -0.25)
			(stroke
				(width 0.15)
				(type solid)
			)
			(layer "F.Fab")
		)
		(fp_line
			(start 0.504 0.248)
			(end -0.494 0.248)
			(stroke
				(width 0.15)
				(type solid)
			)
			(layer "F.Fab")
		)
		(fp_line
			(start -0.494 0.248)
			(end -0.494 -0.25)
			(stroke
				(width 0.15)
				(type solid)
			)
			(layer "F.Fab")
		)
		(fp_text user "License: Apache-2.0"
			(at -0.939 5.799 90)
			(layer "F.Fab")
			(effects
				(font
					(size 0.7 0.7)
					(thickness 0.15)
				)
				(justify left bottom)
			)
		)
		(fp_text user "Author: Antmicro"
			(at -0.939 3.399 90)
			(layer "F.Fab")
			(effects
				(font
					(size 0.7 0.7)
					(thickness 0.15)
				)
				(justify left bottom)
			)
		)
		(fp_text user "${REFERENCE}"
			(at -0.939 4.599 90)
			(layer "F.Fab")
			(effects
				(font
					(size 0.7 0.7)
					(thickness 0.15)
				)
				(justify left bottom)
			)
		)
		(pad "1" smd roundrect
			(at -0.48 0 90)
			(size 0.59 0.64)
			(layers "F.Cu" "F.Mask" "F.Paste")
			(roundrect_rratio 0.25)
			(net 3 "GND")
			(pintype "passive")
		)
		(pad "2" smd roundrect
			(at 0.48 0 90)
			(size 0.59 0.64)
			(layers "F.Cu" "F.Mask" "F.Paste")
			(roundrect_rratio 0.25)
			(net 9 "+3V3")
			(pintype "passive")
		)
	)
	(footprint "antmicro-footprints:TP_SMD_0.75mm"
		(layer "F.Cu")
		(at 139.55 157.3)
		(property "Reference" "TP603"
			(at 0.95 -0.55 180)
			(layer "F.SilkS")
			(effects
				(font
					(size 0.7 0.7)
					(thickness 0.15)
				)
				(justify left bottom)
			)
		)
		(property "Value" "TP_0.75mm_SMD"
			(at 0 1.2 0)
			(layer "F.Fab")
			(effects
				(font
					(size 0.7 0.7)
					(thickness 0.15)
				)
				(justify left bottom)
			)
		)
		(property "MPN" ""
			(at 0 0 0)
			(unlocked yes)
			(layer "F.Fab")
			(hide yes)
			(effects
				(font
					(size 1 1)
					(thickness 0.15)
				)
			)
		)
		(property "Manufacturer" ""
			(at 0 0 0)
			(unlocked yes)
			(layer "F.Fab")
			(hide yes)
			(effects
				(font
					(size 1 1)
					(thickness 0.15)
				)
			)
		)
		(property "Author" "Antmicro"
			(at 0 0 0)
			(unlocked yes)
			(layer "F.Fab")
			(hide yes)
			(effects
				(font
					(size 1 1)
					(thickness 0.15)
				)
			)
		)
		(property "License" "Apache-2.0"
			(at 0 0 0)
			(unlocked yes)
			(layer "F.Fab")
			(hide yes)
			(effects
				(font
					(size 1 1)
					(thickness 0.15)
				)
			)
		)
		(sheetname "/CSI/")
		(sheetfile "csi.kicad_sch")
		(attr exclude_from_pos_files exclude_from_bom)
		(fp_circle
			(center 0 0)
			(end 0.475 0)
			(stroke
				(width 0.05)
				(type default)
			)
			(fill no)
			(layer "F.CrtYd")
		)
		(fp_text user "Author: Antmicro"
			(at -0.4 3.901 0)
			(layer "F.Fab")
			(effects
				(font
					(size 0.7 0.7)
					(thickness 0.15)
				)
				(justify left bottom)
			)
		)
		(fp_text user "${REFERENCE}"
			(at -0.4 2.7 0)
			(layer "F.Fab")
			(effects
				(font
					(size 0.7 0.7)
					(thickness 0.15)
				)
				(justify left bottom)
			)
		)
		(fp_text user "License: Apache-2.0"
			(at -0.4 5.101 0)
			(layer "F.Fab")
			(effects
				(font
					(size 0.7 0.7)
					(thickness 0.15)
				)
				(justify left bottom)
			)
		)
		(pad "1" smd circle
			(at 0 0)
			(size 0.75 0.75)
			(layers "F.Cu" "F.Mask")
			(net 20 "/CSI/CSI_5V")
			(pinfunction "1")
			(pintype "passive")
		)
	)
	(footprint "antmicro-footprints:R_0402_1005Metric"
		(layer "F.Cu")
		(at 133.342962 124.7415)
		(descr "Resistor SMD 0402")
		(tags "resistor SMD 0402")
		(property "Reference" "R212"
			(at -1.195 8.075 0)
			(layer "F.SilkS")
			(effects
				(font
					(size 0.7 0.7)
					(thickness 0.15)
				)
				(justify left bottom)
			)
		)
		(property "Value" "R_100k_0402"
			(at -1.011843 1.772047 0)
			(layer "F.Fab")
			(effects
				(font
					(size 0.7 0.7)
					(thickness 0.15)
				)
				(justify left bottom)
			)
		)
		(property "Datasheet" "https://www.bourns.com/docs/product-datasheets/cr.pdf"
			(at 0 0 0)
			(layer "F.Fab")
			(hide yes)
			(effects
				(font
					(size 1.27 1.27)
					(thickness 0.15)
				)
			)
		)
		(property "Manufacturer" "Bourns"
			(at 0 0 0)
			(unlocked yes)
			(layer "F.Fab")
			(hide yes)
			(effects
				(font
					(size 1 1)
					(thickness 0.15)
				)
			)
		)
		(property "MPN" "CR0402-FX-1003GLF"
			(at 0 0 0)
			(unlocked yes)
			(layer "F.Fab")
			(hide yes)
			(effects
				(font
					(size 1 1)
					(thickness 0.15)
				)
			)
		)
		(property "Val" "100k"
			(at 0 0 0)
			(unlocked yes)
			(layer "F.Fab")
			(hide yes)
			(effects
				(font
					(size 1 1)
					(thickness 0.15)
				)
			)
		)
		(property "License" "Apache-2.0"
			(at 0 0 0)
			(unlocked yes)
			(layer "F.Fab")
			(hide yes)
			(effects
				(font
					(size 1 1)
					(thickness 0.15)
				)
			)
		)
		(property "Author" "Antmicro"
			(at 0 0 0)
			(unlocked yes)
			(layer "F.Fab")
			(hide yes)
			(effects
				(font
					(size 1 1)
					(thickness 0.15)
				)
			)
		)
		(property "Tolerance" "1%"
			(at 0 0 0)
			(unlocked yes)
			(layer "F.Fab")
			(hide yes)
			(effects
				(font
					(size 1 1)
					(thickness 0.15)
				)
			)
		)
		(sheetname "/Compute module/")
		(sheetfile "compute-module.kicad_sch")
		(attr smd)
		(fp_rect
			(start -0.925 -0.47)
			(end 0.925 0.47)
			(stroke
				(width 0.05)
				(type default)
			)
			(fill no)
			(layer "F.CrtYd")
		)
		(fp_rect
			(start -0.5 -0.25)
			(end 0.5 0.25)
			(stroke
				(width 0.15)
				(type solid)
			)
			(fill no)
			(layer "F.Fab")
		)
		(fp_text user "License: Apache-2.0"
			(at -0.95 5.169 0)
			(layer "F.Fab")
			(effects
				(font
					(size 0.7 0.7)
					(thickness 0.15)
				)
				(justify left bottom)
			)
		)
		(fp_text user "Author: Antmicro"
			(at -0.95 4.169 0)
			(layer "F.Fab")
			(effects
				(font
					(size 0.7 0.7)
					(thickness 0.15)
				)
				(justify left bottom)
			)
		)
		(fp_text user "${REFERENCE}"
			(at -0.95 3.168 0)
			(layer "F.Fab")
			(effects
				(font
					(size 0.7 0.7)
					(thickness 0.15)
				)
				(justify left bottom)
			)
		)
		(pad "1" smd roundrect
			(at -0.48 0)
			(size 0.59 0.64)
			(layers "F.Cu" "F.Mask" "F.Paste")
			(roundrect_rratio 0.25)
			(net 3 "GND")
			(pintype "passive")
		)
		(pad "2" smd roundrect
			(at 0.48 0)
			(size 0.59 0.64)
			(layers "F.Cu" "F.Mask" "F.Paste")
			(roundrect_rratio 0.25)
			(net 2 "Net-(D203-A)")
			(pintype "passive")
		)
	)
	(footprint "antmicro-footprints:TP_SMD_0.75mm"
		(layer "F.Cu")
		(at 39.3 160.4)
		(property "Reference" "TP310"
			(at 0.45 3.8 90)
			(layer "F.SilkS")
			(effects
				(font
					(size 0.7 0.7)
					(thickness 0.15)
				)
				(justify left bottom)
			)
		)
		(property "Value" "TP_0.75mm_SMD"
			(at 0 1.2 0)
			(layer "F.Fab")
			(effects
				(font
					(size 0.7 0.7)
					(thickness 0.15)
				)
				(justify left bottom)
			)
		)
		(property "MPN" ""
			(at 0 0 0)
			(unlocked yes)
			(layer "F.Fab")
			(hide yes)
			(effects
				(font
					(size 1 1)
					(thickness 0.15)
				)
			)
		)
		(property "Manufacturer" ""
			(at 0 0 0)
			(unlocked yes)
			(layer "F.Fab")
			(hide yes)
			(effects
				(font
					(size 1 1)
					(thickness 0.15)
				)
			)
		)
		(property "Author" "Antmicro"
			(at 0 0 0)
			(unlocked yes)
			(layer "F.Fab")
			(hide yes)
			(effects
				(font
					(size 1 1)
					(thickness 0.15)
				)
			)
		)
		(property "License" "Apache-2.0"
			(at 0 0 0)
			(unlocked yes)
			(layer "F.Fab")
			(hide yes)
			(effects
				(font
					(size 1 1)
					(thickness 0.15)
				)
			)
		)
		(sheetname "/Supply/")
		(sheetfile "supply.kicad_sch")
		(attr exclude_from_pos_files exclude_from_bom)
		(fp_circle
			(center 0 0)
			(end 0.475 0)
			(stroke
				(width 0.05)
				(type default)
			)
			(fill no)
			(layer "F.CrtYd")
		)
		(fp_text user "License: Apache-2.0"
			(at -0.4 5.101 0)
			(layer "F.Fab")
			(effects
				(font
					(size 0.7 0.7)
					(thickness 0.15)
				)
				(justify left bottom)
			)
		)
		(fp_text user "${REFERENCE}"
			(at -0.4 2.7 0)
			(layer "F.Fab")
			(effects
				(font
					(size 0.7 0.7)
					(thickness 0.15)
				)
				(justify left bottom)
			)
		)
		(fp_text user "Author: Antmicro"
			(at -0.4 3.901 0)
			(layer "F.Fab")
			(effects
				(font
					(size 0.7 0.7)
					(thickness 0.15)
				)
				(justify left bottom)
			)
		)
		(pad "1" smd circle
			(at 0 0)
			(size 0.75 0.75)
			(layers "F.Cu" "F.Mask")
			(net 21 "/Supply/VCC_IN")
			(pinfunction "1")
			(pintype "passive")
		)
	)
	(footprint "antmicro-footprints:R_0402_1005Metric"
		(layer "F.Cu")
		(at 74.007962 136.0465 180)
		(descr "Resistor SMD 0402")
		(tags "resistor SMD 0402")
		(property "Reference" "R920"
			(at 3.613659 -0.447803 0)
			(layer "F.SilkS")
			(effects
				(font
					(size 0.7 0.7)
					(thickness 0.15)
				)
				(justify right bottom)
			)
		)
		(property "Value" "R_470R_0402"
			(at -1.011843 1.772047 0)
			(layer "F.Fab")
			(effects
				(font
					(size 0.7 0.7)
					(thickness 0.15)
				)
				(justify right bottom)
			)
		)
		(property "Datasheet" "https://www.bourns.com/docs/product-datasheets/cr.pdf"
			(at 0 0 180)
			(layer "F.Fab")
			(hide yes)
			(effects
				(font
					(size 1.27 1.27)
					(thickness 0.15)
				)
			)
		)
		(property "Manufacturer" "Bourns"
			(at 0 0 180)
			(unlocked yes)
			(layer "F.Fab")
			(hide yes)
			(effects
				(font
					(size 1 1)
					(thickness 0.15)
				)
			)
		)
		(property "MPN" "CR0402-FX-4700GLF"
			(at 0 0 180)
			(unlocked yes)
			(layer "F.Fab")
			(hide yes)
			(effects
				(font
					(size 1 1)
					(thickness 0.15)
				)
			)
		)
		(property "Val" "470R"
			(at 0 0 180)
			(unlocked yes)
			(layer "F.Fab")
			(hide yes)
			(effects
				(font
					(size 1 1)
					(thickness 0.15)
				)
			)
		)
		(property "License" "Apache-2.0"
			(at 0 0 180)
			(unlocked yes)
			(layer "F.Fab")
			(hide yes)
			(effects
				(font
					(size 1 1)
					(thickness 0.15)
				)
			)
		)
		(property "Author" "Antmicro"
			(at 0 0 180)
			(unlocked yes)
			(layer "F.Fab")
			(hide yes)
			(effects
				(font
					(size 1 1)
					(thickness 0.15)
				)
			)
		)
		(property "Tolerance" "1%"
			(at 0 0 180)
			(unlocked yes)
			(layer "F.Fab")
			(hide yes)
			(effects
				(font
					(size 1 1)
					(thickness 0.15)
				)
			)
		)
		(sheetname "/USB/")
		(sheetfile "usb.kicad_sch")
		(attr smd)
		(fp_rect
			(start -0.925 -0.47)
			(end 0.925 0.47)
			(stroke
				(width 0.05)
				(type default)
			)
			(fill no)
			(layer "F.CrtYd")
		)
		(fp_rect
			(start -0.5 -0.25)
			(end 0.5 0.25)
			(stroke
				(width 0.15)
				(type solid)
			)
			(fill no)
			(layer "F.Fab")
		)
		(fp_text user "${REFERENCE}"
			(at -0.95 3.168 180)
			(layer "F.Fab")
			(effects
				(font
					(size 0.7 0.7)
					(thickness 0.15)
				)
				(justify left bottom)
			)
		)
		(fp_text user "License: Apache-2.0"
			(at -0.95 5.169 180)
			(layer "F.Fab")
			(effects
				(font
					(size 0.7 0.7)
					(thickness 0.15)
				)
				(justify left bottom)
			)
		)
		(fp_text user "Author: Antmicro"
			(at -0.95 4.169 180)
			(layer "F.Fab")
			(effects
				(font
					(size 0.7 0.7)
					(thickness 0.15)
				)
				(justify left bottom)
			)
		)
		(pad "1" smd roundrect
			(at -0.48 0 180)
			(size 0.59 0.64)
			(layers "F.Cu" "F.Mask" "F.Paste")
			(roundrect_rratio 0.25)
			(net 487 "Net-(D911-A)")
			(pintype "passive")
		)
		(pad "2" smd roundrect
			(at 0.48 0 180)
			(size 0.59 0.64)
			(layers "F.Cu" "F.Mask" "F.Paste")
			(roundrect_rratio 0.25)
			(net 27 "/USB/USB_3V3")
			(pintype "passive")
		)
	)
	(footprint "antmicro-footprints:R_0402_1005Metric"
		(layer "F.Cu")
		(at 120.3 157.9915 180)
		(descr "Resistor SMD 0402")
		(tags "resistor SMD 0402")
		(property "Reference" "R223"
			(at -4.3 -0.175 180)
			(layer "F.SilkS")
			(effects
				(font
					(size 0.7 0.7)
					(thickness 0.15)
				)
				(justify left bottom)
			)
		)
		(property "Value" "R_0R_0402"
			(at -1.011843 1.772047 180)
			(layer "F.Fab")
			(effects
				(font
					(size 0.7 0.7)
					(thickness 0.15)
				)
				(justify left bottom)
			)
		)
		(property "Datasheet" "https://industrial.panasonic.com/cdbs/www-data/pdf/RDA0000/AOA0000C301.pdf"
			(at 0 0 180)
			(layer "F.Fab")
			(hide yes)
			(effects
				(font
					(size 1.27 1.27)
					(thickness 0.15)
				)
			)
		)
		(property "Manufacturer" "Panasonic"
			(at 0 0 180)
			(unlocked yes)
			(layer "F.Fab")
			(hide yes)
			(effects
				(font
					(size 1 1)
					(thickness 0.15)
				)
			)
		)
		(property "MPN" "ERJ2GE0R00X"
			(at 0 0 180)
			(unlocked yes)
			(layer "F.Fab")
			(hide yes)
			(effects
				(font
					(size 1 1)
					(thickness 0.15)
				)
			)
		)
		(property "Val" "0R"
			(at 0 0 180)
			(unlocked yes)
			(layer "F.Fab")
			(hide yes)
			(effects
				(font
					(size 1 1)
					(thickness 0.15)
				)
			)
		)
		(property "License" "Apache-2.0"
			(at 0 0 180)
			(unlocked yes)
			(layer "F.Fab")
			(hide yes)
			(effects
				(font
					(size 1 1)
					(thickness 0.15)
				)
			)
		)
		(property "Author" "Antmicro"
			(at 0 0 180)
			(unlocked yes)
			(layer "F.Fab")
			(hide yes)
			(effects
				(font
					(size 1 1)
					(thickness 0.15)
				)
			)
		)
		(property "Tolerance" "~"
			(at 0 0 180)
			(unlocked yes)
			(layer "F.Fab")
			(hide yes)
			(effects
				(font
					(size 1 1)
					(thickness 0.15)
				)
			)
		)
		(property "Current" "1A"
			(at 0 0 180)
			(unlocked yes)
			(layer "F.Fab")
			(hide yes)
			(effects
				(font
					(size 1 1)
					(thickness 0.15)
				)
			)
		)
		(sheetname "/Compute module/")
		(sheetfile "compute-module.kicad_sch")
		(attr smd)
		(fp_rect
			(start -0.925 -0.47)
			(end 0.925 0.47)
			(stroke
				(width 0.05)
				(type default)
			)
			(fill no)
			(layer "F.CrtYd")
		)
		(fp_rect
			(start -0.5 -0.25)
			(end 0.5 0.25)
			(stroke
				(width 0.15)
				(type solid)
			)
			(fill no)
			(layer "F.Fab")
		)
		(fp_text user "License: Apache-2.0"
			(at -0.95 5.169 180)
			(layer "F.Fab")
			(effects
				(font
					(size 0.7 0.7)
					(thickness 0.15)
				)
				(justify left bottom)
			)
		)
		(fp_text user "Author: Antmicro"
			(at -0.95 4.169 180)
			(layer "F.Fab")
			(effects
				(font
					(size 0.7 0.7)
					(thickness 0.15)
				)
				(justify left bottom)
			)
		)
		(fp_text user "${REFERENCE}"
			(at -0.95 3.168 180)
			(layer "F.Fab")
			(effects
				(font
					(size 0.7 0.7)
					(thickness 0.15)
				)
				(justify left bottom)
			)
		)
		(pad "1" smd roundrect
			(at -0.48 0 180)
			(size 0.59 0.64)
			(layers "F.Cu" "F.Mask" "F.Paste")
			(roundrect_rratio 0.25)
			(net 158 "/Compute module/NVMe.RX3_N")
			(pintype "passive")
		)
		(pad "2" smd roundrect
			(at 0.48 0 180)
			(size 0.59 0.64)
			(layers "F.Cu" "F.Mask" "F.Paste")
			(roundrect_rratio 0.25)
			(net 156 "/Compute module/R3_N")
			(pintype "passive")
		)
	)
)
